(kicad_pcb
	(version 20260206)
	(generator "pcbnew")
	(generator_version "10.0")
	(general
		(thickness 1.6)
		(legacy_teardrops no)
	)
	(paper "A4")
	(title_block
		(title "04192023_DAF0TMB3IC0_F0TG_MB_C_brd_V02_OCP.brd")
		(comment 1 "Grand Teton / footprints 301-308 of 8354")
	)
	(layers
		(0 "F.Cu" signal "TOP")
		(4 "In1.Cu" signal "GND")
		(6 "In2.Cu" signal "IN1")
		(8 "In3.Cu" signal "GND1")
		(10 "In4.Cu" signal "IN2")
		(12 "In5.Cu" signal "GND2")
		(14 "In6.Cu" signal "IN3")
		(16 "In7.Cu" signal "GND3")
		(18 "In8.Cu" signal "VCC")
		(20 "In9.Cu" signal "VCC1")
		(22 "In10.Cu" signal "GND4")
		(24 "In11.Cu" signal "IN4")
		(26 "In12.Cu" signal "GND5")
		(28 "In13.Cu" signal "IN5")
		(30 "In14.Cu" signal "GND6")
		(32 "In15.Cu" signal "IN6")
		(34 "In16.Cu" signal "GND7")
		(2 "B.Cu" signal "BOTTOM")
		(9 "F.Adhes" user "F.Adhesive")
		(11 "B.Adhes" user "B.Adhesive")
		(13 "F.Paste" user "Package Geometry/Pastemask Top")
		(15 "B.Paste" user "Package Geometry/Pastemask Bottom")
		(5 "F.SilkS" user "Ref Des/Silkscreen Top")
		(7 "B.SilkS" user "Ref Des/Silkscreen Bottom")
		(1 "F.Mask" user "Board Geometry/Soldermask Top")
		(3 "B.Mask" user "Board Geometry/Soldermask Bottom")
		(17 "Dwgs.User" user "User.Drawings")
		(19 "Cmts.User" user "User.Comments")
		(21 "Eco1.User" user "User.Eco1")
		(23 "Eco2.User" user "User.Eco2")
		(25 "Edge.Cuts" user "Board Geometry/Outline")
		(27 "Margin" user)
		(31 "F.CrtYd" user "Package Geometry/Place Bound Top")
		(29 "B.CrtYd" user "Package Geometry/Place Bound Bottom")
		(35 "F.Fab" user "Ref Des/Assembly Top")
		(33 "B.Fab" user "Ref Des/Assembly Bottom")
	)
	(footprint ""
		(layer "F.Cu")
		(at 363.217206 -261.747762 -90)
		(property "Reference" "C2641"
			(at 0 0 270)
			(layer "F.SilkS")
			(hide yes)
			(effects
				(font
					(size 1.27 1.27)
				)
			)
		)
		(property "Value" ""
			(at 0 0 270)
			(layer "F.Fab")
			(effects
				(font
					(size 1.27 1.27)
				)
			)
		)
		(duplicate_pad_numbers_are_jumpers no)
		(fp_line
			(start -0.7874 0.4064)
			(end -0.7874 -0.4064)
			(stroke
				(width 0.1524)
				(type default)
			)
			(layer "F.SilkS")
		)
		(fp_line
			(start 0.7874 0.4064)
			(end -0.7874 0.4064)
			(stroke
				(width 0.1524)
				(type default)
			)
			(layer "F.SilkS")
		)
		(fp_line
			(start -0.7874 -0.4064)
			(end 0.7874 -0.4064)
			(stroke
				(width 0.1524)
				(type default)
			)
			(layer "F.SilkS")
		)
		(fp_line
			(start 0.7874 -0.4064)
			(end 0.7874 0.4064)
			(stroke
				(width 0.1524)
				(type default)
			)
			(layer "F.SilkS")
		)
		(fp_line
			(start -0.67945 0.3048)
			(end -0.67945 -0.305054)
			(stroke
				(width 0.1)
				(type default)
			)
			(layer "F.Fab")
		)
		(fp_line
			(start -0.12065 0.3048)
			(end -0.67945 0.3048)
			(stroke
				(width 0.1)
				(type default)
			)
			(layer "F.Fab")
		)
		(fp_line
			(start 0.120396 0.3048)
			(end 0.120396 0.2794)
			(stroke
				(width 0.1)
				(type default)
			)
			(layer "F.Fab")
		)
		(fp_line
			(start 0.67945 0.3048)
			(end 0.120396 0.3048)
			(stroke
				(width 0.1)
				(type default)
			)
			(layer "F.Fab")
		)
		(fp_line
			(start -0.12065 0.2794)
			(end -0.12065 0.3048)
			(stroke
				(width 0.1)
				(type default)
			)
			(layer "F.Fab")
		)
		(fp_line
			(start 0.120396 0.2794)
			(end -0.12065 0.2794)
			(stroke
				(width 0.1)
				(type default)
			)
			(layer "F.Fab")
		)
		(fp_line
			(start -0.12065 -0.2794)
			(end 0.12065 -0.2794)
			(stroke
				(width 0.1)
				(type default)
			)
			(layer "F.Fab")
		)
		(fp_line
			(start 0.12065 -0.2794)
			(end 0.12065 -0.3048)
			(stroke
				(width 0.1)
				(type default)
			)
			(layer "F.Fab")
		)
		(fp_line
			(start 0.12065 -0.3048)
			(end 0.67945 -0.3048)
			(stroke
				(width 0.1)
				(type default)
			)
			(layer "F.Fab")
		)
		(fp_line
			(start 0.67945 -0.3048)
			(end 0.67945 0.3048)
			(stroke
				(width 0.1)
				(type default)
			)
			(layer "F.Fab")
		)
		(fp_line
			(start -0.67945 -0.305054)
			(end -0.12065 -0.305054)
			(stroke
				(width 0.1)
				(type default)
			)
			(layer "F.Fab")
		)
		(fp_line
			(start -0.12065 -0.305054)
			(end -0.12065 -0.2794)
			(stroke
				(width 0.1)
				(type default)
			)
			(layer "F.Fab")
		)
		(pad "1" smd circle
			(at -0.40005 0 270)
			(size 0 0)
			(layers "F.Cu" "F.Mask" "F.Paste")
			(net "PVDD11_S3_P0")
		)
		(pad "2" smd circle
			(at 0.40005 0 270)
			(size 0 0)
			(layers "F.Cu" "F.Mask" "F.Paste")
			(net "GND")
		)
	)
	(footprint ""
		(layer "F.Cu")
		(at 418.25164 -383.88163 -90)
		(property "Reference" "C848"
			(at 0 0 270)
			(layer "F.SilkS")
			(hide yes)
			(effects
				(font
					(size 1.27 1.27)
				)
			)
		)
		(property "Value" ""
			(at 0 0 270)
			(layer "F.Fab")
			(effects
				(font
					(size 1.27 1.27)
				)
			)
		)
		(duplicate_pad_numbers_are_jumpers no)
		(fp_line
			(start -0.299974 0.150114)
			(end -0.299974 -0.150114)
			(stroke
				(width 0.1)
				(type default)
			)
			(layer "F.Fab")
		)
		(fp_line
			(start 0.299974 0.150114)
			(end -0.299974 0.150114)
			(stroke
				(width 0.1)
				(type default)
			)
			(layer "F.Fab")
		)
		(fp_line
			(start -0.299974 -0.150114)
			(end 0.299974 -0.150114)
			(stroke
				(width 0.1)
				(type default)
			)
			(layer "F.Fab")
		)
		(fp_line
			(start 0.299974 -0.150114)
			(end 0.299974 0.150114)
			(stroke
				(width 0.1)
				(type default)
			)
			(layer "F.Fab")
		)
		(pad "1" smd rect
			(at -0.2667 0 270)
			(size 0.3048 0.381)
			(layers "F.Cu" "F.Mask" "F.Paste")
			(net "P5E_CPU0_P2_TX_C_DN<10>")
		)
		(pad "2" smd rect
			(at 0.2667 0 270)
			(size 0.3048 0.381)
			(layers "F.Cu" "F.Mask" "F.Paste")
			(net "P5E_CPU0_P2_TX_DN<10>")
		)
	)
	(footprint ""
		(layer "F.Cu")
		(at 301.419768 -145.877788 180)
		(property "Reference" "C1336"
			(at 0 0 180)
			(layer "F.SilkS")
			(hide yes)
			(effects
				(font
					(size 1.27 1.27)
				)
			)
		)
		(property "Value" ""
			(at 0 0 180)
			(layer "F.Fab")
			(effects
				(font
					(size 1.27 1.27)
				)
			)
		)
		(duplicate_pad_numbers_are_jumpers no)
		(fp_line
			(start 0.7874 0.4064)
			(end -0.7874 0.4064)
			(stroke
				(width 0.1524)
				(type default)
			)
			(layer "F.SilkS")
		)
		(fp_line
			(start 0.7874 -0.4064)
			(end 0.7874 0.4064)
			(stroke
				(width 0.1524)
				(type default)
			)
			(layer "F.SilkS")
		)
		(fp_line
			(start -0.7874 0.4064)
			(end -0.7874 -0.4064)
			(stroke
				(width 0.1524)
				(type default)
			)
			(layer "F.SilkS")
		)
		(fp_line
			(start -0.7874 -0.4064)
			(end 0.7874 -0.4064)
			(stroke
				(width 0.1524)
				(type default)
			)
			(layer "F.SilkS")
		)
		(fp_line
			(start 0.67945 0.3048)
			(end 0.120396 0.3048)
			(stroke
				(width 0.1)
				(type default)
			)
			(layer "F.Fab")
		)
		(fp_line
			(start 0.67945 -0.3048)
			(end 0.67945 0.3048)
			(stroke
				(width 0.1)
				(type default)
			)
			(layer "F.Fab")
		)
		(fp_line
			(start 0.12065 -0.2794)
			(end 0.12065 -0.3048)
			(stroke
				(width 0.1)
				(type default)
			)
			(layer "F.Fab")
		)
		(fp_line
			(start 0.12065 -0.3048)
			(end 0.67945 -0.3048)
			(stroke
				(width 0.1)
				(type default)
			)
			(layer "F.Fab")
		)
		(fp_line
			(start 0.120396 0.3048)
			(end 0.120396 0.2794)
			(stroke
				(width 0.1)
				(type default)
			)
			(layer "F.Fab")
		)
		(fp_line
			(start 0.120396 0.2794)
			(end -0.12065 0.2794)
			(stroke
				(width 0.1)
				(type default)
			)
			(layer "F.Fab")
		)
		(fp_line
			(start -0.12065 0.3048)
			(end -0.67945 0.3048)
			(stroke
				(width 0.1)
				(type default)
			)
			(layer "F.Fab")
		)
		(fp_line
			(start -0.12065 0.2794)
			(end -0.12065 0.3048)
			(stroke
				(width 0.1)
				(type default)
			)
			(layer "F.Fab")
		)
		(fp_line
			(start -0.12065 -0.2794)
			(end 0.12065 -0.2794)
			(stroke
				(width 0.1)
				(type default)
			)
			(layer "F.Fab")
		)
		(fp_line
			(start -0.12065 -0.305054)
			(end -0.12065 -0.2794)
			(stroke
				(width 0.1)
				(type default)
			)
			(layer "F.Fab")
		)
		(fp_line
			(start -0.67945 0.3048)
			(end -0.67945 -0.305054)
			(stroke
				(width 0.1)
				(type default)
			)
			(layer "F.Fab")
		)
		(fp_line
			(start -0.67945 -0.305054)
			(end -0.12065 -0.305054)
			(stroke
				(width 0.1)
				(type default)
			)
			(layer "F.Fab")
		)
		(pad "1" smd circle
			(at -0.40005 0 180)
			(size 0 0)
			(layers "F.Cu" "F.Mask" "F.Paste")
			(net "P3V3_AUX")
		)
		(pad "2" smd circle
			(at 0.40005 0 180)
			(size 0 0)
			(layers "F.Cu" "F.Mask" "F.Paste")
			(net "GND")
		)
	)
	(footprint ""
		(layer "F.Cu")
		(at 131.90728 -27.25928)
		(property "Reference" "R340"
			(at 0 0 0)
			(layer "F.SilkS")
			(hide yes)
			(effects
				(font
					(size 1.27 1.27)
				)
			)
		)
		(property "Value" ""
			(at 0 0 0)
			(layer "F.Fab")
			(effects
				(font
					(size 1.27 1.27)
				)
			)
		)
		(duplicate_pad_numbers_are_jumpers no)
		(fp_line
			(start -0.32512 -0.175006)
			(end 0.32512 -0.175006)
			(stroke
				(width 0.1)
				(type default)
			)
			(layer "F.Fab")
		)
		(fp_line
			(start -0.32512 0.175006)
			(end -0.32512 -0.175006)
			(stroke
				(width 0.1)
				(type default)
			)
			(layer "F.Fab")
		)
		(fp_line
			(start 0.32512 -0.175006)
			(end 0.32512 0.175006)
			(stroke
				(width 0.1)
				(type default)
			)
			(layer "F.Fab")
		)
		(fp_line
			(start 0.32512 0.175006)
			(end -0.32512 0.175006)
			(stroke
				(width 0.1)
				(type default)
			)
			(layer "F.Fab")
		)
		(pad "1" smd rect
			(at -0.2667 0)
			(size 0.3048 0.381)
			(layers "F.Cu" "F.Mask" "F.Paste")
			(net "USB2_CPU0_P0_DN")
		)
		(pad "2" smd rect
			(at 0.2667 0 180)
			(size 0.3048 0.381)
			(layers "F.Cu" "F.Mask" "F.Paste")
			(net "GND")
		)
	)
	(footprint ""
		(layer "F.Cu")
		(at 366.64392 -395.066774 -90)
		(property "Reference" "R635"
			(at 0 0 270)
			(layer "F.SilkS")
			(hide yes)
			(effects
				(font
					(size 1.27 1.27)
				)
			)
		)
		(property "Value" ""
			(at 0 0 270)
			(layer "F.Fab")
			(effects
				(font
					(size 1.27 1.27)
				)
			)
		)
		(duplicate_pad_numbers_are_jumpers no)
		(fp_line
			(start -0.32512 0.175006)
			(end -0.32512 -0.175006)
			(stroke
				(width 0.1)
				(type default)
			)
			(layer "F.Fab")
		)
		(fp_line
			(start 0.32512 0.175006)
			(end -0.32512 0.175006)
			(stroke
				(width 0.1)
				(type default)
			)
			(layer "F.Fab")
		)
		(fp_line
			(start -0.32512 -0.175006)
			(end 0.32512 -0.175006)
			(stroke
				(width 0.1)
				(type default)
			)
			(layer "F.Fab")
		)
		(fp_line
			(start 0.32512 -0.175006)
			(end 0.32512 0.175006)
			(stroke
				(width 0.1)
				(type default)
			)
			(layer "F.Fab")
		)
		(pad "1" smd rect
			(at -0.2667 0 270)
			(size 0.3048 0.381)
			(layers "F.Cu" "F.Mask" "F.Paste")
			(net "CLK_100M_RETIMER_CPU0_P3_DN")
		)
		(pad "2" smd rect
			(at 0.2667 0 90)
			(size 0.3048 0.381)
			(layers "F.Cu" "F.Mask" "F.Paste")
			(net "GND")
		)
	)
	(footprint ""
		(layer "F.Cu")
		(at 193.369438 -427.693328 -90)
		(property "Reference" "U190"
			(at 2.258568 1.78308 0)
			(unlocked yes)
			(layer "F.SilkS")
			(effects
				(font
					(size 0.7874 0.5842)
					(thickness 0.1524)
				)
				(justify left)
			)
		)
		(property "Value" ""
			(at 0 0 270)
			(layer "F.Fab")
			(effects
				(font
					(size 1.27 1.27)
				)
			)
		)
		(duplicate_pad_numbers_are_jumpers no)
		(fp_line
			(start -1.603248 1.500124)
			(end -1.603248 -1.500124)
			(stroke
				(width 0.1524)
				(type default)
			)
			(layer "F.SilkS")
		)
		(fp_line
			(start 1.603248 1.500124)
			(end -1.603248 1.500124)
			(stroke
				(width 0.1524)
				(type default)
			)
			(layer "F.SilkS")
		)
		(fp_line
			(start -1.603248 -1.500124)
			(end 1.603248 -1.500124)
			(stroke
				(width 0.1524)
				(type default)
			)
			(layer "F.SilkS")
		)
		(fp_line
			(start 1.603248 -1.500124)
			(end 1.603248 1.500124)
			(stroke
				(width 0.1524)
				(type default)
			)
			(layer "F.SilkS")
		)
		(fp_line
			(start -0.700024 1.500124)
			(end 0.700024 1.500124)
			(stroke
				(width 0.1)
				(type default)
			)
			(layer "F.Fab")
		)
		(fp_line
			(start 0.700024 1.500124)
			(end 0.700024 0.219964)
			(stroke
				(width 0.1)
				(type default)
			)
			(layer "F.Fab")
		)
		(fp_line
			(start -1.249934 1.169924)
			(end -0.700024 1.169924)
			(stroke
				(width 0.1)
				(type default)
			)
			(layer "F.Fab")
		)
		(fp_line
			(start -0.700024 1.169924)
			(end -0.700024 1.500124)
			(stroke
				(width 0.1)
				(type default)
			)
			(layer "F.Fab")
		)
		(fp_line
			(start -1.249934 0.729996)
			(end -1.249934 1.169924)
			(stroke
				(width 0.1)
				(type default)
			)
			(layer "F.Fab")
		)
		(fp_line
			(start -0.6985 0.729996)
			(end -1.249934 0.729996)
			(stroke
				(width 0.1)
				(type default)
			)
			(layer "F.Fab")
		)
		(fp_line
			(start 0.700024 0.219964)
			(end 1.249934 0.219964)
			(stroke
				(width 0.1)
				(type default)
			)
			(layer "F.Fab")
		)
		(fp_line
			(start 1.249934 0.219964)
			(end 1.249934 -0.219964)
			(stroke
				(width 0.1)
				(type default)
			)
			(layer "F.Fab")
		)
		(fp_line
			(start 0.700024 -0.219964)
			(end 0.700024 -1.500124)
			(stroke
				(width 0.1)
				(type default)
			)
			(layer "F.Fab")
		)
		(fp_line
			(start 1.249934 -0.219964)
			(end 0.700024 -0.219964)
			(stroke
				(width 0.1)
				(type default)
			)
			(layer "F.Fab")
		)
		(fp_line
			(start -1.249934 -0.729996)
			(end -0.6985 -0.729996)
			(stroke
				(width 0.1)
				(type default)
			)
			(layer "F.Fab")
		)
		(fp_line
			(start -0.6985 -0.729996)
			(end -0.6985 0.729996)
			(stroke
				(width 0.1)
				(type default)
			)
			(layer "F.Fab")
		)
		(fp_line
			(start -1.249934 -1.169924)
			(end -1.249934 -0.729996)
			(stroke
				(width 0.1)
				(type default)
			)
			(layer "F.Fab")
		)
		(fp_line
			(start -0.700024 -1.169924)
			(end -1.249934 -1.169924)
			(stroke
				(width 0.1)
				(type default)
			)
			(layer "F.Fab")
		)
		(fp_line
			(start -0.700024 -1.500124)
			(end -0.700024 -1.169924)
			(stroke
				(width 0.1)
				(type default)
			)
			(layer "F.Fab")
		)
		(fp_line
			(start 0.700024 -1.500124)
			(end -0.700024 -1.500124)
			(stroke
				(width 0.1)
				(type default)
			)
			(layer "F.Fab")
		)
		(fp_rect
			(start -0.700024 1.500124)
			(end 0.700024 -1.500124)
			(stroke
				(width 0)
				(type default)
			)
			(fill no)
			(layer "F.Fab")
		)
		(pad "D" smd rect
			(at 0.999998 0 180)
			(size 0.8128 0.9144)
			(layers "F.Cu" "F.Mask" "F.Paste")
			(net "FM_PDB_BUF_EN_R1")
		)
		(pad "G" smd rect
			(at -0.999998 -0.94996 180)
			(size 0.8128 0.9144)
			(layers "F.Cu" "F.Mask" "F.Paste")
			(net "FM_PDB_BUF_EN_R1_N")
		)
		(pad "S" smd rect
			(at -0.999998 0.94996 180)
			(size 0.8128 0.9144)
			(layers "F.Cu" "F.Mask" "F.Paste")
			(net "GND")
		)
	)
	(footprint ""
		(layer "F.Cu")
		(at 302.09617 -407.79446)
		(property "Reference" "R962"
			(at 0 0 0)
			(layer "F.SilkS")
			(hide yes)
			(effects
				(font
					(size 1.27 1.27)
				)
			)
		)
		(property "Value" ""
			(at 0 0 0)
			(layer "F.Fab")
			(effects
				(font
					(size 1.27 1.27)
				)
			)
		)
		(duplicate_pad_numbers_are_jumpers no)
		(fp_line
			(start -1.2954 -0.5842)
			(end 1.2954 -0.5842)
			(stroke
				(width 0.1524)
				(type default)
			)
			(layer "F.SilkS")
		)
		(fp_line
			(start -1.2954 0.5842)
			(end -1.2954 -0.5842)
			(stroke
				(width 0.1524)
				(type default)
			)
			(layer "F.SilkS")
		)
		(fp_line
			(start 1.2954 -0.5842)
			(end 1.2954 0.5842)
			(stroke
				(width 0.1524)
				(type default)
			)
			(layer "F.SilkS")
		)
		(fp_line
			(start 1.2954 0.5842)
			(end -1.2954 0.5842)
			(stroke
				(width 0.1524)
				(type default)
			)
			(layer "F.SilkS")
		)
		(fp_line
			(start -1.1938 -0.406654)
			(end -0.8636 -0.406654)
			(stroke
				(width 0.1)
				(type default)
			)
			(layer "F.Fab")
		)
		(fp_line
			(start -1.1938 0.4064)
			(end -1.1938 -0.406654)
			(stroke
				(width 0.1)
				(type default)
			)
			(layer "F.Fab")
		)
		(fp_line
			(start -0.8636 -0.4572)
			(end 0.8636 -0.4572)
			(stroke
				(width 0.1)
				(type default)
			)
			(layer "F.Fab")
		)
		(fp_line
			(start -0.8636 -0.406654)
			(end -0.8636 -0.4572)
			(stroke
				(width 0.1)
				(type default)
			)
			(layer "F.Fab")
		)
		(fp_line
			(start -0.8636 0.4064)
			(end -1.1938 0.4064)
			(stroke
				(width 0.1)
				(type default)
			)
			(layer "F.Fab")
		)
		(fp_line
			(start -0.8636 0.4318)
			(end -0.8636 0.4064)
			(stroke
				(width 0.1)
				(type default)
			)
			(layer "F.Fab")
		)
		(fp_line
			(start -0.8636 0.4572)
			(end -0.8636 0.4318)
			(stroke
				(width 0.1)
				(type default)
			)
			(layer "F.Fab")
		)
		(fp_line
			(start 0.8636 -0.4572)
			(end 0.8636 -0.406654)
			(stroke
				(width 0.1)
				(type default)
			)
			(layer "F.Fab")
		)
		(fp_line
			(start 0.8636 -0.406654)
			(end 1.1938 -0.406654)
			(stroke
				(width 0.1)
				(type default)
			)
			(layer "F.Fab")
		)
		(fp_line
			(start 0.8636 0.4064)
			(end 0.8636 0.4572)
			(stroke
				(width 0.1)
				(type default)
			)
			(layer "F.Fab")
		)
		(fp_line
			(start 0.8636 0.4572)
			(end -0.8636 0.4572)
			(stroke
				(width 0.1)
				(type default)
			)
			(layer "F.Fab")
		)
		(fp_line
			(start 1.1938 -0.406654)
			(end 1.1938 0.4064)
			(stroke
				(width 0.1)
				(type default)
			)
			(layer "F.Fab")
		)
		(fp_line
			(start 1.1938 0.4064)
			(end 0.8636 0.4064)
			(stroke
				(width 0.1)
				(type default)
			)
			(layer "F.Fab")
		)
		(pad "1" smd rect
			(at -0.7366 0 270)
			(size 0.7112 0.8128)
			(layers "F.Cu" "F.Mask" "F.Paste")
			(net "P0V9_CPU0_RT0_2A_2D")
		)
		(pad "2" smd rect
			(at 0.7366 0 270)
			(size 0.7112 0.8128)
			(layers "F.Cu" "F.Mask" "F.Paste")
			(net "P0V9_CPU0_RT0_2A")
		)
	)
	(footprint ""
		(layer "F.Cu")
		(at 479.621342 -212.758528)
		(property "Reference" "DB1"
			(at 1.409954 2.969514 0)
			(unlocked yes)
			(layer "F.SilkS")
			(effects
				(font
					(size 0.7874 0.5842)
					(thickness 0.1524)
				)
				(justify left)
			)
		)
		(property "Value" ""
			(at 0 0 0)
			(layer "F.Fab")
			(effects
				(font
					(size 1.27 1.27)
				)
			)
		)
		(duplicate_pad_numbers_are_jumpers no)
		(fp_line
			(start -3.330702 -4.771136)
			(end 3.330702 -4.771136)
			(stroke
				(width 0.1524)
				(type default)
			)
			(layer "F.SilkS")
		)
		(fp_line
			(start 0 4.011168)
			(end -3.330702 -4.771136)
			(stroke
				(width 0.1524)
				(type default)
			)
			(layer "F.SilkS")
		)
		(fp_line
			(start 3.330702 -4.771136)
			(end 0 4.011168)
			(stroke
				(width 0.1524)
				(type default)
			)
			(layer "F.SilkS")
		)
		(fp_line
			(start -3.330702 -4.771136)
			(end 3.330702 -4.771136)
			(stroke
				(width 0.1)
				(type default)
			)
			(layer "F.Fab")
		)
		(fp_line
			(start 0 4.011168)
			(end -3.330702 -4.771136)
			(stroke
				(width 0.1)
				(type default)
			)
			(layer "F.Fab")
		)
		(fp_line
			(start 3.330702 -4.771136)
			(end 0 4.011168)
			(stroke
				(width 0.1)
				(type default)
			)
			(layer "F.Fab")
		)
		(pad "1" thru_hole circle
			(at 0 0)
			(size 2.159 2.159)
			(drill 1.7018)
			(layers "*.Cu" "*.Mask")
			(remove_unused_layers no)
			(net "T1_GND")
			(clearance 0.0254)
			(thermal_gap 0.0254)
		)
		(pad "2" thru_hole circle
			(at -1.27 -3.348736)
			(size 2.159 2.159)
			(drill 1.7018)
			(layers "*.Cu" "*.Mask")
			(remove_unused_layers no)
			(net "TDR_SE_45_OHM_TOP")
			(clearance 0.0254)
			(thermal_gap 0.0254)
		)
		(pad "3" thru_hole circle
			(at 1.27 -3.348736)
			(size 2.159 2.159)
			(drill 1.7018)
			(layers "*.Cu" "*.Mask")
			(remove_unused_layers no)
			(net "TDR_SE_45_OHM_TOP")
			(clearance 0.0254)
			(thermal_gap 0.0254)
		)
	)
)
